(kicad_pcb
	(version 20260206)
	(generator "pcbnew")
	(generator_version "10.0")
	(general
		(thickness 1.6)
		(legacy_teardrops no)
	)
	(paper "A4")
	(title_block
		(title "04192023_DAF0TMB3IC0_F0TG_MB_C_brd_V02_OCP.brd")
		(comment 1 "Grand Teton / footprint 2350 of 8354 (J19), pads 1-113 of 291")
	)
	(layers
		(0 "F.Cu" signal "TOP")
		(4 "In1.Cu" signal "GND")
		(6 "In2.Cu" signal "IN1")
		(8 "In3.Cu" signal "GND1")
		(10 "In4.Cu" signal "IN2")
		(12 "In5.Cu" signal "GND2")
		(14 "In6.Cu" signal "IN3")
		(16 "In7.Cu" signal "GND3")
		(18 "In8.Cu" signal "VCC")
		(20 "In9.Cu" signal "VCC1")
		(22 "In10.Cu" signal "GND4")
		(24 "In11.Cu" signal "IN4")
		(26 "In12.Cu" signal "GND5")
		(28 "In13.Cu" signal "IN5")
		(30 "In14.Cu" signal "GND6")
		(32 "In15.Cu" signal "IN6")
		(34 "In16.Cu" signal "GND7")
		(2 "B.Cu" signal "BOTTOM")
		(9 "F.Adhes" user "F.Adhesive")
		(11 "B.Adhes" user "B.Adhesive")
		(13 "F.Paste" user "Package Geometry/Pastemask Top")
		(15 "B.Paste" user "Package Geometry/Pastemask Bottom")
		(5 "F.SilkS" user "Ref Des/Silkscreen Top")
		(7 "B.SilkS" user "Ref Des/Silkscreen Bottom")
		(1 "F.Mask" user "Board Geometry/Soldermask Top")
		(3 "B.Mask" user "Board Geometry/Soldermask Bottom")
		(17 "Dwgs.User" user "User.Drawings")
		(19 "Cmts.User" user "User.Comments")
		(21 "Eco1.User" user "User.Eco1")
		(23 "Eco2.User" user "User.Eco2")
		(25 "Edge.Cuts" user "Board Geometry/Outline")
		(27 "Margin" user)
		(31 "F.CrtYd" user "Package Geometry/Place Bound Top")
		(29 "B.CrtYd" user "Package Geometry/Place Bound Bottom")
		(35 "F.Fab" user "Ref Des/Assembly Top")
		(33 "B.Fab" user "Ref Des/Assembly Bottom")
	)
	(footprint ""
		(layer "F.Cu")
		(at 282.685998 -255.560068 180)
		(property "Reference" "J19"
			(at -2.2098 -81.984088 0)
			(unlocked yes)
			(layer "F.SilkS")
			(effects
				(font
					(size 0.7874 0.5842)
					(thickness 0.1524)
				)
			)
		)
		(property "Value" ""
			(at 0 0 180)
			(layer "F.Fab")
			(effects
				(font
					(size 1.27 1.27)
				)
			)
		)
		(duplicate_pad_numbers_are_jumpers no)
		(pad "1" smd rect
			(at -2.050034 -63.324994 90)
			(size 0.519938 1.4986)
			(layers "F.Cu" "F.Mask" "F.Paste")
			(net "P12V_MEM_CPU0")
		)
		(pad "2" smd rect
			(at -2.050034 -62.47511 90)
			(size 0.519938 1.4986)
			(layers "F.Cu" "F.Mask" "F.Paste")
			(net "Net_2291")
		)
		(pad "3" smd rect
			(at -2.050034 -61.624972 90)
			(size 0.519938 1.4986)
			(layers "F.Cu" "F.Mask" "F.Paste")
			(net "P3V3_AUX")
		)
		(pad "4" smd rect
			(at -2.050034 -60.775088 90)
			(size 0.519938 1.4986)
			(layers "F.Cu" "F.Mask" "F.Paste")
			(net "I3C_SPD_DDRD_CPU0_SCL")
		)
		(pad "5" smd rect
			(at -2.050034 -59.92495 90)
			(size 0.519938 1.4986)
			(layers "F.Cu" "F.Mask" "F.Paste")
			(net "I3C_SPD_DDRD_CPU0_SDA")
		)
		(pad "6" smd rect
			(at -2.050034 -59.075066 90)
			(size 0.519938 1.4986)
			(layers "F.Cu" "F.Mask" "F.Paste")
			(net "GND")
		)
		(pad "7" smd rect
			(at -2.050034 -58.224928 90)
			(size 0.519938 1.4986)
			(layers "F.Cu" "F.Mask" "F.Paste")
			(net "M_D_CPU0_SA_DQ<0>")
		)
		(pad "8" smd rect
			(at -2.050034 -57.375044 90)
			(size 0.519938 1.4986)
			(layers "F.Cu" "F.Mask" "F.Paste")
			(net "GND")
		)
		(pad "9" smd rect
			(at -2.050034 -56.524906 90)
			(size 0.519938 1.4986)
			(layers "F.Cu" "F.Mask" "F.Paste")
			(net "M_D_CPU0_SA_DQ<1>")
		)
		(pad "10" smd rect
			(at -2.050034 -55.675022 90)
			(size 0.519938 1.4986)
			(layers "F.Cu" "F.Mask" "F.Paste")
			(net "GND")
		)
		(pad "11" smd rect
			(at -2.050034 -54.824884 90)
			(size 0.519938 1.4986)
			(layers "F.Cu" "F.Mask" "F.Paste")
			(net "M_D_CPU0_SA_DQS_DP<0>")
		)
		(pad "12" smd rect
			(at -2.050034 -53.975 90)
			(size 0.519938 1.4986)
			(layers "F.Cu" "F.Mask" "F.Paste")
			(net "M_D_CPU0_SA_DQS_DN<0>")
		)
		(pad "13" smd rect
			(at -2.050034 -53.125116 90)
			(size 0.519938 1.4986)
			(layers "F.Cu" "F.Mask" "F.Paste")
			(net "GND")
		)
		(pad "14" smd rect
			(at -2.050034 -52.274978 90)
			(size 0.519938 1.4986)
			(layers "F.Cu" "F.Mask" "F.Paste")
			(net "M_D_CPU0_SA_DQ<4>")
		)
		(pad "15" smd rect
			(at -2.050034 -51.425094 90)
			(size 0.519938 1.4986)
			(layers "F.Cu" "F.Mask" "F.Paste")
			(net "GND")
		)
		(pad "16" smd rect
			(at -2.050034 -50.574956 90)
			(size 0.519938 1.4986)
			(layers "F.Cu" "F.Mask" "F.Paste")
			(net "M_D_CPU0_SA_DQ<5>")
		)
		(pad "17" smd rect
			(at -2.050034 -49.725072 90)
			(size 0.519938 1.4986)
			(layers "F.Cu" "F.Mask" "F.Paste")
			(net "GND")
		)
		(pad "18" smd rect
			(at -2.050034 -48.874934 90)
			(size 0.519938 1.4986)
			(layers "F.Cu" "F.Mask" "F.Paste")
			(net "M_D_CPU0_SA_DQ<8>")
		)
		(pad "19" smd rect
			(at -2.050034 -48.02505 90)
			(size 0.519938 1.4986)
			(layers "F.Cu" "F.Mask" "F.Paste")
			(net "GND")
		)
		(pad "20" smd rect
			(at -2.050034 -47.174912 90)
			(size 0.519938 1.4986)
			(layers "F.Cu" "F.Mask" "F.Paste")
			(net "M_D_CPU0_SA_DQ<9>")
		)
		(pad "21" smd rect
			(at -2.050034 -46.325028 90)
			(size 0.519938 1.4986)
			(layers "F.Cu" "F.Mask" "F.Paste")
			(net "GND")
		)
		(pad "22" smd rect
			(at -2.050034 -45.47489 90)
			(size 0.519938 1.4986)
			(layers "F.Cu" "F.Mask" "F.Paste")
			(net "M_D_CPU0_SA_DQS_DP<1>")
		)
		(pad "23" smd rect
			(at -2.050034 -44.625006 90)
			(size 0.519938 1.4986)
			(layers "F.Cu" "F.Mask" "F.Paste")
			(net "M_D_CPU0_SA_DQS_DN<1>")
		)
		(pad "24" smd rect
			(at -2.050034 -43.775122 90)
			(size 0.519938 1.4986)
			(layers "F.Cu" "F.Mask" "F.Paste")
			(net "GND")
		)
		(pad "25" smd rect
			(at -2.050034 -42.924984 90)
			(size 0.519938 1.4986)
			(layers "F.Cu" "F.Mask" "F.Paste")
			(net "M_D_CPU0_SA_DQ<12>")
		)
		(pad "26" smd rect
			(at -2.050034 -42.0751 90)
			(size 0.519938 1.4986)
			(layers "F.Cu" "F.Mask" "F.Paste")
			(net "GND")
		)
		(pad "27" smd rect
			(at -2.050034 -41.224962 90)
			(size 0.519938 1.4986)
			(layers "F.Cu" "F.Mask" "F.Paste")
			(net "M_D_CPU0_SA_DQ<13>")
		)
		(pad "28" smd rect
			(at -2.050034 -40.375078 90)
			(size 0.519938 1.4986)
			(layers "F.Cu" "F.Mask" "F.Paste")
			(net "GND")
		)
		(pad "29" smd rect
			(at -2.050034 -39.52494 90)
			(size 0.519938 1.4986)
			(layers "F.Cu" "F.Mask" "F.Paste")
			(net "M_D_CPU0_SA_DQ<16>")
		)
		(pad "30" smd rect
			(at -2.050034 -38.675056 90)
			(size 0.519938 1.4986)
			(layers "F.Cu" "F.Mask" "F.Paste")
			(net "GND")
		)
		(pad "31" smd rect
			(at -2.050034 -37.824918 90)
			(size 0.519938 1.4986)
			(layers "F.Cu" "F.Mask" "F.Paste")
			(net "M_D_CPU0_SA_DQ<17>")
		)
		(pad "32" smd rect
			(at -2.050034 -36.975034 90)
			(size 0.519938 1.4986)
			(layers "F.Cu" "F.Mask" "F.Paste")
			(net "GND")
		)
		(pad "33" smd rect
			(at -2.050034 -36.124896 90)
			(size 0.519938 1.4986)
			(layers "F.Cu" "F.Mask" "F.Paste")
			(net "M_D_CPU0_SA_DQS_DP<2>")
		)
		(pad "34" smd rect
			(at -2.050034 -35.275012 90)
			(size 0.519938 1.4986)
			(layers "F.Cu" "F.Mask" "F.Paste")
			(net "M_D_CPU0_SA_DQS_DN<2>")
		)
		(pad "35" smd rect
			(at -2.050034 -34.425128 90)
			(size 0.519938 1.4986)
			(layers "F.Cu" "F.Mask" "F.Paste")
			(net "GND")
		)
		(pad "36" smd rect
			(at -2.050034 -33.57499 90)
			(size 0.519938 1.4986)
			(layers "F.Cu" "F.Mask" "F.Paste")
			(net "M_D_CPU0_SA_DQ<20>")
		)
		(pad "37" smd rect
			(at -2.050034 -32.725106 90)
			(size 0.519938 1.4986)
			(layers "F.Cu" "F.Mask" "F.Paste")
			(net "GND")
		)
		(pad "38" smd rect
			(at -2.050034 -31.874968 90)
			(size 0.519938 1.4986)
			(layers "F.Cu" "F.Mask" "F.Paste")
			(net "M_D_CPU0_SA_DQ<21>")
		)
		(pad "39" smd rect
			(at -2.050034 -31.025084 90)
			(size 0.519938 1.4986)
			(layers "F.Cu" "F.Mask" "F.Paste")
			(net "GND")
		)
		(pad "40" smd rect
			(at -2.050034 -30.174946 90)
			(size 0.519938 1.4986)
			(layers "F.Cu" "F.Mask" "F.Paste")
			(net "M_D_CPU0_SA_DQ<24>")
		)
		(pad "41" smd rect
			(at -2.050034 -29.325062 90)
			(size 0.519938 1.4986)
			(layers "F.Cu" "F.Mask" "F.Paste")
			(net "GND")
		)
		(pad "42" smd rect
			(at -2.050034 -28.474924 90)
			(size 0.519938 1.4986)
			(layers "F.Cu" "F.Mask" "F.Paste")
			(net "M_D_CPU0_SA_DQ<25>")
		)
		(pad "43" smd rect
			(at -2.050034 -27.62504 90)
			(size 0.519938 1.4986)
			(layers "F.Cu" "F.Mask" "F.Paste")
			(net "GND")
		)
		(pad "44" smd rect
			(at -2.050034 -26.774902 90)
			(size 0.519938 1.4986)
			(layers "F.Cu" "F.Mask" "F.Paste")
			(net "M_D_CPU0_SA_DQS_DP<3>")
		)
		(pad "45" smd rect
			(at -2.050034 -25.925018 90)
			(size 0.519938 1.4986)
			(layers "F.Cu" "F.Mask" "F.Paste")
			(net "M_D_CPU0_SA_DQS_DN<3>")
		)
		(pad "46" smd rect
			(at -2.050034 -25.07488 90)
			(size 0.519938 1.4986)
			(layers "F.Cu" "F.Mask" "F.Paste")
			(net "GND")
		)
		(pad "47" smd rect
			(at -2.050034 -24.224996 90)
			(size 0.519938 1.4986)
			(layers "F.Cu" "F.Mask" "F.Paste")
			(net "M_D_CPU0_SA_DQ<28>")
		)
		(pad "48" smd rect
			(at -2.050034 -23.375112 90)
			(size 0.519938 1.4986)
			(layers "F.Cu" "F.Mask" "F.Paste")
			(net "GND")
		)
		(pad "49" smd rect
			(at -2.050034 -22.524974 90)
			(size 0.519938 1.4986)
			(layers "F.Cu" "F.Mask" "F.Paste")
			(net "M_D_CPU0_SA_DQ<29>")
		)
		(pad "50" smd rect
			(at -2.050034 -21.67509 90)
			(size 0.519938 1.4986)
			(layers "F.Cu" "F.Mask" "F.Paste")
			(net "GND")
		)
		(pad "51" smd rect
			(at -2.050034 -20.824952 90)
			(size 0.519938 1.4986)
			(layers "F.Cu" "F.Mask" "F.Paste")
			(net "M_D_CPU0_SA_CB<0>")
		)
		(pad "52" smd rect
			(at -2.050034 -19.975068 90)
			(size 0.519938 1.4986)
			(layers "F.Cu" "F.Mask" "F.Paste")
			(net "GND")
		)
		(pad "53" smd rect
			(at -2.050034 -19.12493 90)
			(size 0.519938 1.4986)
			(layers "F.Cu" "F.Mask" "F.Paste")
			(net "M_D_CPU0_SA_CB<1>")
		)
		(pad "54" smd rect
			(at -2.050034 -18.275046 90)
			(size 0.519938 1.4986)
			(layers "F.Cu" "F.Mask" "F.Paste")
			(net "GND")
		)
		(pad "55" smd rect
			(at -2.050034 -17.424908 90)
			(size 0.519938 1.4986)
			(layers "F.Cu" "F.Mask" "F.Paste")
			(net "M_D_CPU0_SA_DQS_DP<4>")
		)
		(pad "56" smd rect
			(at -2.050034 -16.575024 90)
			(size 0.519938 1.4986)
			(layers "F.Cu" "F.Mask" "F.Paste")
			(net "M_D_CPU0_SA_DQS_DN<4>")
		)
		(pad "57" smd rect
			(at -2.050034 -15.724886 90)
			(size 0.519938 1.4986)
			(layers "F.Cu" "F.Mask" "F.Paste")
			(net "GND")
		)
		(pad "58" smd rect
			(at -2.050034 -14.875002 90)
			(size 0.519938 1.4986)
			(layers "F.Cu" "F.Mask" "F.Paste")
			(net "M_D_CPU0_SA_CB<4>")
		)
		(pad "59" smd rect
			(at -2.050034 -14.025118 90)
			(size 0.519938 1.4986)
			(layers "F.Cu" "F.Mask" "F.Paste")
			(net "GND")
		)
		(pad "60" smd rect
			(at -2.050034 -13.17498 90)
			(size 0.519938 1.4986)
			(layers "F.Cu" "F.Mask" "F.Paste")
			(net "M_D_CPU0_SA_CB<5>")
		)
		(pad "61" smd rect
			(at -2.050034 -12.325096 90)
			(size 0.519938 1.4986)
			(layers "F.Cu" "F.Mask" "F.Paste")
			(net "GND")
		)
		(pad "62" smd rect
			(at -2.050034 -11.474958 90)
			(size 0.519938 1.4986)
			(layers "F.Cu" "F.Mask" "F.Paste")
			(net "M_D_CPU0_ALERT_N")
		)
		(pad "63" smd rect
			(at -2.050034 -10.625074 90)
			(size 0.519938 1.4986)
			(layers "F.Cu" "F.Mask" "F.Paste")
			(net "GND")
		)
		(pad "64" smd rect
			(at -2.050034 -9.774936 90)
			(size 0.519938 1.4986)
			(layers "F.Cu" "F.Mask" "F.Paste")
			(net "M_D_CPU0_SA_CS_N<0>")
		)
		(pad "65" smd rect
			(at -2.050034 -8.925052 90)
			(size 0.519938 1.4986)
			(layers "F.Cu" "F.Mask" "F.Paste")
			(net "GND")
		)
		(pad "66" smd rect
			(at -2.050034 -8.074914 90)
			(size 0.519938 1.4986)
			(layers "F.Cu" "F.Mask" "F.Paste")
			(net "M_D_CPU0_SA_CA<0>")
		)
		(pad "67" smd rect
			(at -2.050034 -7.22503 90)
			(size 0.519938 1.4986)
			(layers "F.Cu" "F.Mask" "F.Paste")
			(net "GND")
		)
		(pad "68" smd rect
			(at -2.050034 -6.374892 90)
			(size 0.519938 1.4986)
			(layers "F.Cu" "F.Mask" "F.Paste")
			(net "M_D_CPU0_SA_CA<2>")
		)
		(pad "69" smd rect
			(at -2.050034 -5.525008 90)
			(size 0.519938 1.4986)
			(layers "F.Cu" "F.Mask" "F.Paste")
			(net "GND")
		)
		(pad "70" smd rect
			(at -2.050034 -4.675124 90)
			(size 0.519938 1.4986)
			(layers "F.Cu" "F.Mask" "F.Paste")
			(net "M_D_CPU0_SA_CA<4>")
		)
		(pad "71" smd rect
			(at -2.050034 -3.824986 90)
			(size 0.519938 1.4986)
			(layers "F.Cu" "F.Mask" "F.Paste")
			(net "GND")
		)
		(pad "72" smd rect
			(at -2.050034 -2.975102 90)
			(size 0.519938 1.4986)
			(layers "F.Cu" "F.Mask" "F.Paste")
			(net "M_D_CPU0_SA_CA<6>")
		)
		(pad "73" smd rect
			(at -2.050034 -2.124964 90)
			(size 0.519938 1.4986)
			(layers "F.Cu" "F.Mask" "F.Paste")
			(net "GND")
		)
		(pad "74" smd rect
			(at -2.050034 -1.27508 90)
			(size 0.519938 1.4986)
			(layers "F.Cu" "F.Mask" "F.Paste")
			(net "M_D_CPU0_SA_PAR")
		)
		(pad "75" smd rect
			(at -2.050034 -0.424942 90)
			(size 0.519938 1.4986)
			(layers "F.Cu" "F.Mask" "F.Paste")
			(net "GND")
		)
		(pad "76" smd rect
			(at -2.050034 5.525008 90)
			(size 0.519938 1.4986)
			(layers "F.Cu" "F.Mask" "F.Paste")
			(net "M_D_CPU0_SB_CA<0>")
		)
		(pad "77" smd rect
			(at -2.050034 6.374892 90)
			(size 0.519938 1.4986)
			(layers "F.Cu" "F.Mask" "F.Paste")
			(net "GND")
		)
		(pad "78" smd rect
			(at -2.050034 7.22503 90)
			(size 0.519938 1.4986)
			(layers "F.Cu" "F.Mask" "F.Paste")
			(net "M_D_CPU0_SB_CA<2>")
		)
		(pad "79" smd rect
			(at -2.050034 8.074914 90)
			(size 0.519938 1.4986)
			(layers "F.Cu" "F.Mask" "F.Paste")
			(net "GND")
		)
		(pad "80" smd rect
			(at -2.050034 8.925052 90)
			(size 0.519938 1.4986)
			(layers "F.Cu" "F.Mask" "F.Paste")
			(net "M_D_CPU0_SB_CA<4>")
		)
		(pad "81" smd rect
			(at -2.050034 9.774936 90)
			(size 0.519938 1.4986)
			(layers "F.Cu" "F.Mask" "F.Paste")
			(net "GND")
		)
		(pad "82" smd rect
			(at -2.050034 10.625074 90)
			(size 0.519938 1.4986)
			(layers "F.Cu" "F.Mask" "F.Paste")
			(net "M_D_CPU0_SB_CA<6>")
		)
		(pad "83" smd rect
			(at -2.050034 11.474958 90)
			(size 0.519938 1.4986)
			(layers "F.Cu" "F.Mask" "F.Paste")
			(net "GND")
		)
		(pad "84" smd rect
			(at -2.050034 12.325096 90)
			(size 0.519938 1.4986)
			(layers "F.Cu" "F.Mask" "F.Paste")
			(net "M_D_CPU0_SB_CS_N<0>")
		)
		(pad "85" smd rect
			(at -2.050034 13.17498 90)
			(size 0.519938 1.4986)
			(layers "F.Cu" "F.Mask" "F.Paste")
			(net "GND")
		)
		(pad "86" smd rect
			(at -2.050034 14.025118 90)
			(size 0.519938 1.4986)
			(layers "F.Cu" "F.Mask" "F.Paste")
			(net "M_D_CPU0_SA_RSP<0>")
		)
		(pad "87" smd rect
			(at -2.050034 14.875002 90)
			(size 0.519938 1.4986)
			(layers "F.Cu" "F.Mask" "F.Paste")
			(net "M_D_CPU0_SB_RSP<0>")
		)
		(pad "88" smd rect
			(at -2.050034 15.724886 90)
			(size 0.519938 1.4986)
			(layers "F.Cu" "F.Mask" "F.Paste")
			(net "GND")
		)
		(pad "89" smd rect
			(at -2.050034 16.575024 90)
			(size 0.519938 1.4986)
			(layers "F.Cu" "F.Mask" "F.Paste")
			(net "M_D_CPU0_SB_CB<4>")
		)
		(pad "90" smd rect
			(at -2.050034 17.424908 90)
			(size 0.519938 1.4986)
			(layers "F.Cu" "F.Mask" "F.Paste")
			(net "GND")
		)
		(pad "91" smd rect
			(at -2.050034 18.275046 90)
			(size 0.519938 1.4986)
			(layers "F.Cu" "F.Mask" "F.Paste")
			(net "M_D_CPU0_SB_CB<5>")
		)
		(pad "92" smd rect
			(at -2.050034 19.12493 90)
			(size 0.519938 1.4986)
			(layers "F.Cu" "F.Mask" "F.Paste")
			(net "GND")
		)
		(pad "93" smd rect
			(at -2.050034 19.975068 90)
			(size 0.519938 1.4986)
			(layers "F.Cu" "F.Mask" "F.Paste")
			(net "M_D_CPU0_SB_DQS_DP<9>")
		)
		(pad "94" smd rect
			(at -2.050034 20.824952 90)
			(size 0.519938 1.4986)
			(layers "F.Cu" "F.Mask" "F.Paste")
			(net "M_D_CPU0_SB_DQS_DN<9>")
		)
		(pad "95" smd rect
			(at -2.050034 21.67509 90)
			(size 0.519938 1.4986)
			(layers "F.Cu" "F.Mask" "F.Paste")
			(net "GND")
		)
		(pad "96" smd rect
			(at -2.050034 22.524974 90)
			(size 0.519938 1.4986)
			(layers "F.Cu" "F.Mask" "F.Paste")
			(net "M_D_CPU0_SB_CB<0>")
		)
		(pad "97" smd rect
			(at -2.050034 23.375112 90)
			(size 0.519938 1.4986)
			(layers "F.Cu" "F.Mask" "F.Paste")
			(net "GND")
		)
		(pad "98" smd rect
			(at -2.050034 24.224996 90)
			(size 0.519938 1.4986)
			(layers "F.Cu" "F.Mask" "F.Paste")
			(net "M_D_CPU0_SB_CB<1>")
		)
		(pad "99" smd rect
			(at -2.050034 25.07488 90)
			(size 0.519938 1.4986)
			(layers "F.Cu" "F.Mask" "F.Paste")
			(net "GND")
		)
		(pad "100" smd rect
			(at -2.050034 25.925018 90)
			(size 0.519938 1.4986)
			(layers "F.Cu" "F.Mask" "F.Paste")
			(net "M_D_CPU0_SB_DQ<0>")
		)
		(pad "101" smd rect
			(at -2.050034 26.774902 90)
			(size 0.519938 1.4986)
			(layers "F.Cu" "F.Mask" "F.Paste")
			(net "GND")
		)
		(pad "102" smd rect
			(at -2.050034 27.62504 90)
			(size 0.519938 1.4986)
			(layers "F.Cu" "F.Mask" "F.Paste")
			(net "M_D_CPU0_SB_DQ<1>")
		)
		(pad "103" smd rect
			(at -2.050034 28.474924 90)
			(size 0.519938 1.4986)
			(layers "F.Cu" "F.Mask" "F.Paste")
			(net "GND")
		)
		(pad "104" smd rect
			(at -2.050034 29.325062 90)
			(size 0.519938 1.4986)
			(layers "F.Cu" "F.Mask" "F.Paste")
			(net "M_D_CPU0_SB_DQS_DP<0>")
		)
		(pad "105" smd rect
			(at -2.050034 30.174946 90)
			(size 0.519938 1.4986)
			(layers "F.Cu" "F.Mask" "F.Paste")
			(net "M_D_CPU0_SB_DQS_DN<0>")
		)
		(pad "106" smd rect
			(at -2.050034 31.025084 90)
			(size 0.519938 1.4986)
			(layers "F.Cu" "F.Mask" "F.Paste")
			(net "GND")
		)
		(pad "107" smd rect
			(at -2.050034 31.874968 90)
			(size 0.519938 1.4986)
			(layers "F.Cu" "F.Mask" "F.Paste")
			(net "M_D_CPU0_SB_DQ<4>")
		)
		(pad "108" smd rect
			(at -2.050034 32.725106 90)
			(size 0.519938 1.4986)
			(layers "F.Cu" "F.Mask" "F.Paste")
			(net "GND")
		)
		(pad "109" smd rect
			(at -2.050034 33.57499 90)
			(size 0.519938 1.4986)
			(layers "F.Cu" "F.Mask" "F.Paste")
			(net "M_D_CPU0_SB_DQ<5>")
		)
		(pad "110" smd rect
			(at -2.050034 34.425128 90)
			(size 0.519938 1.4986)
			(layers "F.Cu" "F.Mask" "F.Paste")
			(net "GND")
		)
		(pad "111" smd rect
			(at -2.050034 35.275012 90)
			(size 0.519938 1.4986)
			(layers "F.Cu" "F.Mask" "F.Paste")
			(net "M_D_CPU0_SB_DQ<8>")
		)
		(pad "112" smd rect
			(at -2.050034 36.124896 90)
			(size 0.519938 1.4986)
			(layers "F.Cu" "F.Mask" "F.Paste")
			(net "GND")
		)
		(pad "113" smd rect
			(at -2.050034 36.975034 90)
			(size 0.519938 1.4986)
			(layers "F.Cu" "F.Mask" "F.Paste")
			(net "M_D_CPU0_SB_DQ<9>")
		)
	)
)
